# T6G (Grand Teton) — schematic netlist excerpt (pin names and nets, part order shuffled) for the footprints in the layout excerpt that follows; sources: Cadence DE-HDL packaged netlist, KiCad conversion of 04192023_DAF0TMB3IC0_F0TG_MB_C_brd_V02_OCP.brd

PR53  Q_RES  40.2K 1% CHIP  pkg 0402LF  page 200 : A = P5V_AUX ; B = PVDDCR_CPU1_P0_VMON
R1907  Q_RES  1K 1% CHIP  pkg 0402LF  page 134 : A = P3V3_AUX ; B = OCP_SFF_PRSNT1_R_N

(kicad_pcb
	(version 20260206)
	(generator "pcbnew")
	(generator_version "10.0")
	(general
		(thickness 1.6)
		(legacy_teardrops no)
	)
	(paper "A4")
	(title_block
		(title "04192023_DAF0TMB3IC0_F0TG_MB_C_brd_V02_OCP.brd")
		(comment 1 "Grand Teton / footprints 956-957 of 8354")
	)
	(layers
		(0 "F.Cu" signal "TOP")
		(4 "In1.Cu" signal "GND")
		(6 "In2.Cu" signal "IN1")
		(8 "In3.Cu" signal "GND1")
		(10 "In4.Cu" signal "IN2")
		(12 "In5.Cu" signal "GND2")
		(14 "In6.Cu" signal "IN3")
		(16 "In7.Cu" signal "GND3")
		(18 "In8.Cu" signal "VCC")
		(20 "In9.Cu" signal "VCC1")
		(22 "In10.Cu" signal "GND4")
		(24 "In11.Cu" signal "IN4")
		(26 "In12.Cu" signal "GND5")
		(28 "In13.Cu" signal "IN5")
		(30 "In14.Cu" signal "GND6")
		(32 "In15.Cu" signal "IN6")
		(34 "In16.Cu" signal "GND7")
		(2 "B.Cu" signal "BOTTOM")
		(9 "F.Adhes" user "F.Adhesive")
		(11 "B.Adhes" user "B.Adhesive")
		(13 "F.Paste" user "Package Geometry/Pastemask Top")
		(15 "B.Paste" user "Package Geometry/Pastemask Bottom")
		(5 "F.SilkS" user "Ref Des/Silkscreen Top")
		(7 "B.SilkS" user "Ref Des/Silkscreen Bottom")
		(1 "F.Mask" user "Board Geometry/Soldermask Top")
		(3 "B.Mask" user "Board Geometry/Soldermask Bottom")
		(17 "Dwgs.User" user "User.Drawings")
		(19 "Cmts.User" user "User.Comments")
		(21 "Eco1.User" user "User.Eco1")
		(23 "Eco2.User" user "User.Eco2")
		(25 "Edge.Cuts" user "Board Geometry/Outline")
		(27 "Margin" user)
		(31 "F.CrtYd" user "Package Geometry/Place Bound Top")
		(29 "B.CrtYd" user "Package Geometry/Place Bound Bottom")
		(35 "F.Fab" user "Ref Des/Assembly Top")
		(33 "B.Fab" user "Ref Des/Assembly Bottom")
	)
	(footprint ""
		(layer "F.Cu")
		(at 319.242186 -361.061 90)
		(property "Reference" "PR53"
			(at 0 0 90)
			(layer "F.SilkS")
			(hide yes)
			(effects
				(font
					(size 1.27 1.27)
				)
			)
		)
		(property "Value" ""
			(at 0 0 90)
			(layer "F.Fab")
			(effects
				(font
					(size 1.27 1.27)
				)
			)
		)
		(duplicate_pad_numbers_are_jumpers no)
		(fp_line
			(start 0.7874 -0.4064)
			(end 0.7874 0.4064)
			(stroke
				(width 0.1524)
				(type default)
			)
			(layer "F.SilkS")
		)
		(fp_line
			(start -0.7874 -0.4064)
			(end 0.7874 -0.4064)
			(stroke
				(width 0.1524)
				(type default)
			)
			(layer "F.SilkS")
		)
		(fp_line
			(start 0.7874 0.4064)
			(end -0.7874 0.4064)
			(stroke
				(width 0.1524)
				(type default)
			)
			(layer "F.SilkS")
		)
		(fp_line
			(start -0.7874 0.4064)
			(end -0.7874 -0.4064)
			(stroke
				(width 0.1524)
				(type default)
			)
			(layer "F.SilkS")
		)
		(fp_line
			(start -0.12065 -0.305054)
			(end -0.12065 -0.2794)
			(stroke
				(width 0.1)
				(type default)
			)
			(layer "F.Fab")
		)
		(fp_line
			(start -0.67945 -0.305054)
			(end -0.12065 -0.305054)
			(stroke
				(width 0.1)
				(type default)
			)
			(layer "F.Fab")
		)
		(fp_line
			(start 0.67945 -0.3048)
			(end 0.67945 0.3048)
			(stroke
				(width 0.1)
				(type default)
			)
			(layer "F.Fab")
		)
		(fp_line
			(start 0.12065 -0.3048)
			(end 0.67945 -0.3048)
			(stroke
				(width 0.1)
				(type default)
			)
			(layer "F.Fab")
		)
		(fp_line
			(start 0.12065 -0.2794)
			(end 0.12065 -0.3048)
			(stroke
				(width 0.1)
				(type default)
			)
			(layer "F.Fab")
		)
		(fp_line
			(start -0.12065 -0.2794)
			(end 0.12065 -0.2794)
			(stroke
				(width 0.1)
				(type default)
			)
			(layer "F.Fab")
		)
		(fp_line
			(start 0.120396 0.2794)
			(end -0.12065 0.2794)
			(stroke
				(width 0.1)
				(type default)
			)
			(layer "F.Fab")
		)
		(fp_line
			(start -0.12065 0.2794)
			(end -0.12065 0.3048)
			(stroke
				(width 0.1)
				(type default)
			)
			(layer "F.Fab")
		)
		(fp_line
			(start 0.67945 0.3048)
			(end 0.120396 0.3048)
			(stroke
				(width 0.1)
				(type default)
			)
			(layer "F.Fab")
		)
		(fp_line
			(start 0.120396 0.3048)
			(end 0.120396 0.2794)
			(stroke
				(width 0.1)
				(type default)
			)
			(layer "F.Fab")
		)
		(fp_line
			(start -0.12065 0.3048)
			(end -0.67945 0.3048)
			(stroke
				(width 0.1)
				(type default)
			)
			(layer "F.Fab")
		)
		(fp_line
			(start -0.67945 0.3048)
			(end -0.67945 -0.305054)
			(stroke
				(width 0.1)
				(type default)
			)
			(layer "F.Fab")
		)
		(pad "1" smd circle
			(at -0.40005 0 90)
			(size 0 0)
			(layers "F.Cu" "F.Mask" "F.Paste")
			(net "P5V_AUX")
		)
		(pad "2" smd circle
			(at 0.40005 0 90)
			(size 0 0)
			(layers "F.Cu" "F.Mask" "F.Paste")
			(net "PVDDCR_CPU1_P0_VMON")
		)
	)
	(footprint ""
		(layer "F.Cu")
		(at 453.719946 -106.408728)
		(property "Reference" "R1907"
			(at 0 0 0)
			(layer "F.SilkS")
			(hide yes)
			(effects
				(font
					(size 1.27 1.27)
				)
			)
		)
		(property "Value" ""
			(at 0 0 0)
			(layer "F.Fab")
			(effects
				(font
					(size 1.27 1.27)
				)
			)
		)
		(duplicate_pad_numbers_are_jumpers no)
		(fp_line
			(start -0.7874 -0.4064)
			(end 0.7874 -0.4064)
			(stroke
				(width 0.1524)
				(type default)
			)
			(layer "F.SilkS")
		)
		(fp_line
			(start -0.7874 0.4064)
			(end -0.7874 -0.4064)
			(stroke
				(width 0.1524)
				(type default)
			)
			(layer "F.SilkS")
		)
		(fp_line
			(start 0.7874 -0.4064)
			(end 0.7874 0.4064)
			(stroke
				(width 0.1524)
				(type default)
			)
			(layer "F.SilkS")
		)
		(fp_line
			(start 0.7874 0.4064)
			(end -0.7874 0.4064)
			(stroke
				(width 0.1524)
				(type default)
			)
			(layer "F.SilkS")
		)
		(fp_line
			(start -0.67945 -0.305054)
			(end -0.12065 -0.305054)
			(stroke
				(width 0.1)
				(type default)
			)
			(layer "F.Fab")
		)
		(fp_line
			(start -0.67945 0.3048)
			(end -0.67945 -0.305054)
			(stroke
				(width 0.1)
				(type default)
			)
			(layer "F.Fab")
		)
		(fp_line
			(start -0.12065 -0.305054)
			(end -0.12065 -0.2794)
			(stroke
				(width 0.1)
				(type default)
			)
			(layer "F.Fab")
		)
		(fp_line
			(start -0.12065 -0.2794)
			(end 0.12065 -0.2794)
			(stroke
				(width 0.1)
				(type default)
			)
			(layer "F.Fab")
		)
		(fp_line
			(start -0.12065 0.2794)
			(end -0.12065 0.3048)
			(stroke
				(width 0.1)
				(type default)
			)
			(layer "F.Fab")
		)
		(fp_line
			(start -0.12065 0.3048)
			(end -0.67945 0.3048)
			(stroke
				(width 0.1)
				(type default)
			)
			(layer "F.Fab")
		)
		(fp_line
			(start 0.120396 0.2794)
			(end -0.12065 0.2794)
			(stroke
				(width 0.1)
				(type default)
			)
			(layer "F.Fab")
		)
		(fp_line
			(start 0.120396 0.3048)
			(end 0.120396 0.2794)
			(stroke
				(width 0.1)
				(type default)
			)
			(layer "F.Fab")
		)
		(fp_line
			(start 0.12065 -0.3048)
			(end 0.67945 -0.3048)
			(stroke
				(width 0.1)
				(type default)
			)
			(layer "F.Fab")
		)
		(fp_line
			(start 0.12065 -0.2794)
			(end 0.12065 -0.3048)
			(stroke
				(width 0.1)
				(type default)
			)
			(layer "F.Fab")
		)
		(fp_line
			(start 0.67945 -0.3048)
			(end 0.67945 0.3048)
			(stroke
				(width 0.1)
				(type default)
			)
			(layer "F.Fab")
		)
		(fp_line
			(start 0.67945 0.3048)
			(end 0.120396 0.3048)
			(stroke
				(width 0.1)
				(type default)
			)
			(layer "F.Fab")
		)
		(pad "1" smd circle
			(at -0.40005 0)
			(size 0 0)
			(layers "F.Cu" "F.Mask" "F.Paste")
			(net "P3V3_AUX")
		)
		(pad "2" smd circle
			(at 0.40005 0)
			(size 0 0)
			(layers "F.Cu" "F.Mask" "F.Paste")
			(net "OCP_SFF_PRSNT1_R_N")
		)
	)
)
